# S9S_MB_2U (Grand Teton) — schematic netlist excerpt (pin names and nets, part order shuffled) for the footprints in the layout excerpt that follows; sources: Cadence DE-HDL packaged netlist, KiCad conversion of 03242023_DA0F0TMBIJ0_F0T_Motherboard_J_brd_V01_OCP.brd

R694  Q_RES  33.2 1% CHIP  pkg 0402LF  page 229 : A = I3C_SPD_DDREFGH_CPU0_LVC1_R_SDA ; B = I3C_SPD_DDREFGH_CPU0_LVC1_SDA
R185  Q_RES  100 1% CHIP  pkg 0402LF  page 124 : A = RST_CPU0_BUF_R_N ; B = PVNN_TERM_CPU0

(kicad_pcb
	(version 20260206)
	(generator "pcbnew")
	(generator_version "10.0")
	(general
		(thickness 1.6)
		(legacy_teardrops no)
	)
	(paper "A4")
	(title_block
		(title "03242023_DA0F0TMBIJ0_F0T_Motherboard_J_brd_V01_OCP.brd")
		(comment 1 "Grand Teton / footprints 5615-5616 of 6105")
	)
	(layers
		(0 "F.Cu" signal "TOP")
		(4 "In1.Cu" signal "GND")
		(6 "In2.Cu" signal "IN1")
		(8 "In3.Cu" signal "GND1")
		(10 "In4.Cu" signal "IN2")
		(12 "In5.Cu" signal "GND2")
		(14 "In6.Cu" signal "IN3")
		(16 "In7.Cu" signal "GND3")
		(18 "In8.Cu" signal "VCC")
		(20 "In9.Cu" signal "VCC1")
		(22 "In10.Cu" signal "GND4")
		(24 "In11.Cu" signal "IN4")
		(26 "In12.Cu" signal "GND5")
		(28 "In13.Cu" signal "IN5")
		(30 "In14.Cu" signal "GND6")
		(32 "In15.Cu" signal "IN6")
		(34 "In16.Cu" signal "GND7")
		(2 "B.Cu" signal "BOTTOM")
		(9 "F.Adhes" user "F.Adhesive")
		(11 "B.Adhes" user "B.Adhesive")
		(13 "F.Paste" user "Package Geometry/Pastemask Top")
		(15 "B.Paste" user "Package Geometry/Pastemask Bottom")
		(5 "F.SilkS" user "Ref Des/Silkscreen Top")
		(7 "B.SilkS" user "Ref Des/Silkscreen Bottom")
		(1 "F.Mask" user "Board Geometry/Soldermask Top")
		(3 "B.Mask" user "Board Geometry/Soldermask Bottom")
		(17 "Dwgs.User" user "User.Drawings")
		(19 "Cmts.User" user "User.Comments")
		(21 "Eco1.User" user "User.Eco1")
		(23 "Eco2.User" user "User.Eco2")
		(25 "Edge.Cuts" user "Board Geometry/Outline")
		(27 "Margin" user)
		(31 "F.CrtYd" user "Package Geometry/Place Bound Top")
		(29 "B.CrtYd" user "Package Geometry/Place Bound Bottom")
		(35 "F.Fab" user "Ref Des/Assembly Top")
		(33 "B.Fab" user "Ref Des/Assembly Bottom")
	)
	(footprint ""
		(layer "B.Cu")
		(at 305.533298 -152.179782 180)
		(property "Reference" "R694"
			(at 0 0 0)
			(layer "B.SilkS")
			(hide yes)
			(effects
				(font
					(size 1.27 1.27)
				)
				(justify mirror)
			)
		)
		(property "Value" ""
			(at 0 0 0)
			(layer "B.Fab")
			(effects
				(font
					(size 1.27 1.27)
				)
				(justify mirror)
			)
		)
		(duplicate_pad_numbers_are_jumpers no)
		(fp_line
			(start 0.7874 0.4064)
			(end 0.7874 -0.4064)
			(stroke
				(width 0.1524)
				(type default)
			)
			(layer "B.SilkS")
		)
		(fp_line
			(start 0.7874 -0.4064)
			(end -0.7874 -0.4064)
			(stroke
				(width 0.1524)
				(type default)
			)
			(layer "B.SilkS")
		)
		(fp_line
			(start -0.7874 0.4064)
			(end 0.7874 0.4064)
			(stroke
				(width 0.1524)
				(type default)
			)
			(layer "B.SilkS")
		)
		(fp_line
			(start -0.7874 -0.4064)
			(end -0.7874 0.4064)
			(stroke
				(width 0.1524)
				(type default)
			)
			(layer "B.SilkS")
		)
		(fp_line
			(start 0.67945 0.3048)
			(end 0.67945 -0.305054)
			(stroke
				(width 0.1)
				(type default)
			)
			(layer "B.Fab")
		)
		(fp_line
			(start 0.67945 -0.305054)
			(end 0.12065 -0.305054)
			(stroke
				(width 0.1)
				(type default)
			)
			(layer "B.Fab")
		)
		(fp_line
			(start 0.12065 0.3048)
			(end 0.67945 0.3048)
			(stroke
				(width 0.1)
				(type default)
			)
			(layer "B.Fab")
		)
		(fp_line
			(start 0.12065 0.2794)
			(end 0.12065 0.3048)
			(stroke
				(width 0.1)
				(type default)
			)
			(layer "B.Fab")
		)
		(fp_line
			(start 0.12065 -0.2794)
			(end -0.12065 -0.2794)
			(stroke
				(width 0.1)
				(type default)
			)
			(layer "B.Fab")
		)
		(fp_line
			(start 0.12065 -0.305054)
			(end 0.12065 -0.2794)
			(stroke
				(width 0.1)
				(type default)
			)
			(layer "B.Fab")
		)
		(fp_line
			(start -0.120396 0.3048)
			(end -0.120396 0.2794)
			(stroke
				(width 0.1)
				(type default)
			)
			(layer "B.Fab")
		)
		(fp_line
			(start -0.120396 0.2794)
			(end 0.12065 0.2794)
			(stroke
				(width 0.1)
				(type default)
			)
			(layer "B.Fab")
		)
		(fp_line
			(start -0.12065 -0.2794)
			(end -0.12065 -0.3048)
			(stroke
				(width 0.1)
				(type default)
			)
			(layer "B.Fab")
		)
		(fp_line
			(start -0.12065 -0.3048)
			(end -0.67945 -0.3048)
			(stroke
				(width 0.1)
				(type default)
			)
			(layer "B.Fab")
		)
		(fp_line
			(start -0.67945 0.3048)
			(end -0.120396 0.3048)
			(stroke
				(width 0.1)
				(type default)
			)
			(layer "B.Fab")
		)
		(fp_line
			(start -0.67945 -0.3048)
			(end -0.67945 0.3048)
			(stroke
				(width 0.1)
				(type default)
			)
			(layer "B.Fab")
		)
		(pad "1" smd circle
			(at 0.40005 0)
			(size 0 0)
			(layers "B.Cu" "B.Mask" "B.Paste")
			(net "I3C_SPD_DDREFGH_CPU0_LVC1_R_SDA")
		)
		(pad "2" smd circle
			(at -0.40005 0)
			(size 0 0)
			(layers "B.Cu" "B.Mask" "B.Paste")
			(net "I3C_SPD_DDREFGH_CPU0_LVC1_SDA")
		)
	)
	(footprint ""
		(layer "B.Cu")
		(at 297.942 -258.155948)
		(property "Reference" "R185"
			(at 0 0 0)
			(layer "B.SilkS")
			(hide yes)
			(effects
				(font
					(size 1.27 1.27)
				)
				(justify mirror)
			)
		)
		(property "Value" ""
			(at 0 0 0)
			(layer "B.Fab")
			(effects
				(font
					(size 1.27 1.27)
				)
				(justify mirror)
			)
		)
		(duplicate_pad_numbers_are_jumpers no)
		(fp_line
			(start -0.7874 -0.4064)
			(end -0.7874 0.4064)
			(stroke
				(width 0.1524)
				(type default)
			)
			(layer "B.SilkS")
		)
		(fp_line
			(start -0.7874 0.4064)
			(end 0.7874 0.4064)
			(stroke
				(width 0.1524)
				(type default)
			)
			(layer "B.SilkS")
		)
		(fp_line
			(start 0.7874 -0.4064)
			(end -0.7874 -0.4064)
			(stroke
				(width 0.1524)
				(type default)
			)
			(layer "B.SilkS")
		)
		(fp_line
			(start 0.7874 0.4064)
			(end 0.7874 -0.4064)
			(stroke
				(width 0.1524)
				(type default)
			)
			(layer "B.SilkS")
		)
		(fp_line
			(start -0.67945 -0.3048)
			(end -0.67945 0.3048)
			(stroke
				(width 0.1)
				(type default)
			)
			(layer "B.Fab")
		)
		(fp_line
			(start -0.67945 0.3048)
			(end -0.120396 0.3048)
			(stroke
				(width 0.1)
				(type default)
			)
			(layer "B.Fab")
		)
		(fp_line
			(start -0.12065 -0.3048)
			(end -0.67945 -0.3048)
			(stroke
				(width 0.1)
				(type default)
			)
			(layer "B.Fab")
		)
		(fp_line
			(start -0.12065 -0.2794)
			(end -0.12065 -0.3048)
			(stroke
				(width 0.1)
				(type default)
			)
			(layer "B.Fab")
		)
		(fp_line
			(start -0.120396 0.2794)
			(end 0.12065 0.2794)
			(stroke
				(width 0.1)
				(type default)
			)
			(layer "B.Fab")
		)
		(fp_line
			(start -0.120396 0.3048)
			(end -0.120396 0.2794)
			(stroke
				(width 0.1)
				(type default)
			)
			(layer "B.Fab")
		)
		(fp_line
			(start 0.12065 -0.305054)
			(end 0.12065 -0.2794)
			(stroke
				(width 0.1)
				(type default)
			)
			(layer "B.Fab")
		)
		(fp_line
			(start 0.12065 -0.2794)
			(end -0.12065 -0.2794)
			(stroke
				(width 0.1)
				(type default)
			)
			(layer "B.Fab")
		)
		(fp_line
			(start 0.12065 0.2794)
			(end 0.12065 0.3048)
			(stroke
				(width 0.1)
				(type default)
			)
			(layer "B.Fab")
		)
		(fp_line
			(start 0.12065 0.3048)
			(end 0.67945 0.3048)
			(stroke
				(width 0.1)
				(type default)
			)
			(layer "B.Fab")
		)
		(fp_line
			(start 0.67945 -0.305054)
			(end 0.12065 -0.305054)
			(stroke
				(width 0.1)
				(type default)
			)
			(layer "B.Fab")
		)
		(fp_line
			(start 0.67945 0.3048)
			(end 0.67945 -0.305054)
			(stroke
				(width 0.1)
				(type default)
			)
			(layer "B.Fab")
		)
		(pad "1" smd circle
			(at 0.40005 0 180)
			(size 0 0)
			(layers "B.Cu" "B.Mask" "B.Paste")
			(net "RST_CPU0_BUF_R_N")
		)
		(pad "2" smd circle
			(at -0.40005 0 180)
			(size 0 0)
			(layers "B.Cu" "B.Mask" "B.Paste")
			(net "PVNN_TERM_CPU0")
		)
	)
)
